(kicad_pcb
	(version 20260206)
	(generator "pcbnew")
	(generator_version "10.0")
	(general
		(thickness 1.6)
		(legacy_teardrops no)
	)
	(paper "A4")
	(title_block
		(title "pdpb — Lightning_PDPB_BRD.brd")
		(comment 1 "Lightning (Wiwynn / Facebook NVMe JBOF) / footprints 545-550 of 1140")
	)
	(layers
		(0 "F.Cu" signal "TOP")
		(4 "In1.Cu" signal "L2GND")
		(6 "In2.Cu" signal "L3")
		(8 "In3.Cu" signal "L4VCC")
		(10 "In4.Cu" signal "L5VCC")
		(12 "In5.Cu" signal "L6")
		(14 "In6.Cu" signal "L7GND")
		(2 "B.Cu" signal "BOTTOM")
		(9 "F.Adhes" user "F.Adhesive")
		(11 "B.Adhes" user "B.Adhesive")
		(13 "F.Paste" user "Package Geometry/Pastemask Top")
		(15 "B.Paste" user "Package Geometry/Pastemask Bottom")
		(5 "F.SilkS" user "Ref Des/Silkscreen Top")
		(7 "B.SilkS" user "Ref Des/Silkscreen Bottom")
		(1 "F.Mask" user "Board Geometry/Soldermask Top")
		(3 "B.Mask" user "Board Geometry/Soldermask Bottom")
		(17 "Dwgs.User" user "User.Drawings")
		(19 "Cmts.User" user "User.Comments")
		(21 "Eco1.User" user "User.Eco1")
		(23 "Eco2.User" user "User.Eco2")
		(25 "Edge.Cuts" user "Board Geometry/Outline")
		(27 "Margin" user)
		(31 "F.CrtYd" user "Package Geometry/Place Bound Top")
		(29 "B.CrtYd" user "Package Geometry/Place Bound Bottom")
		(35 "F.Fab" user "Ref Des/Assembly Top")
		(33 "B.Fab" user "Ref Des/Assembly Bottom")
	)
	(footprint ""
		(layer "F.Cu")
		(at 24.003 -363.474 -90)
		(property "Reference" "SR1143"
			(at 0 0 270)
			(layer "F.SilkS")
			(hide yes)
			(effects
				(font
					(size 1.27 1.27)
				)
			)
		)
		(property "Value" "4K7R2F-GP"
			(at 0.064008 -3.993896 270)
			(unlocked yes)
			(layer "F.Fab")
			(hide yes)
			(effects
				(font
					(size 1.016 1.016)
					(thickness 0.1524)
				)
			)
		)
		(property "Device Type" "R402H16"
			(at 0.064008 -5.517896 270)
			(unlocked yes)
			(layer "F.Fab")
			(hide yes)
			(effects
				(font
					(size 1.016 1.016)
					(thickness 0.1524)
				)
			)
		)
		(duplicate_pad_numbers_are_jumpers no)
		(fp_line
			(start -0.508 -0.9398)
			(end -0.508 0.9398)
			(stroke
				(width 0.1524)
				(type default)
			)
			(layer "F.SilkS")
		)
		(fp_line
			(start 0.508 -0.9398)
			(end -0.508 -0.9398)
			(stroke
				(width 0.1524)
				(type default)
			)
			(layer "F.SilkS")
		)
		(fp_rect
			(start -0.508 0.9398)
			(end 0.508 -0.9398)
			(stroke
				(width 0)
				(type default)
			)
			(fill no)
			(layer "F.CrtYd")
		)
		(fp_rect
			(start -0.508 0.9398)
			(end 0.508 -0.9398)
			(stroke
				(width 0)
				(type default)
			)
			(fill no)
			(layer "F.Fab")
		)
		(pad "1" smd custom
			(at 0 -0.4445 270)
			(size 0.1397 0.1397)
			(layers "F.Cu" "F.Mask" "F.Paste")
			(net "P3V3")
			(options
				(clearance outline)
				(anchor circle)
			)
			(primitives
				(gr_poly
					(pts
						(arc
							(start -0.1778 -0.2794)
							(mid -0.249642 -0.249642)
							(end -0.2794 -0.1778)
						)
						(arc
							(start -0.2794 0.1778)
							(mid -0.249642 0.249642)
							(end -0.1778 0.2794)
						)
						(arc
							(start 0.1778 0.2794)
							(mid 0.249642 0.249642)
							(end 0.2794 0.1778)
						)
						(arc
							(start 0.2794 -0.1778)
							(mid 0.249642 -0.249642)
							(end 0.1778 -0.2794)
						)
					)
					(width 0)
					(fill yes)
				)
			)
		)
		(pad "2" smd custom
			(at 0 0.4445 270)
			(size 0.1397 0.1397)
			(layers "F.Cu" "F.Mask" "F.Paste")
			(net "SSD11_CLK0_OE_MOS_N")
			(options
				(clearance outline)
				(anchor circle)
			)
			(primitives
				(gr_poly
					(pts
						(arc
							(start -0.1778 -0.2794)
							(mid -0.249642 -0.249642)
							(end -0.2794 -0.1778)
						)
						(arc
							(start -0.2794 0.1778)
							(mid -0.249642 0.249642)
							(end -0.1778 0.2794)
						)
						(arc
							(start 0.1778 0.2794)
							(mid 0.249642 0.249642)
							(end 0.2794 0.1778)
						)
						(arc
							(start 0.2794 -0.1778)
							(mid 0.249642 -0.249642)
							(end 0.1778 -0.2794)
						)
					)
					(width 0)
					(fill yes)
				)
			)
		)
	)
	(footprint ""
		(layer "F.Cu")
		(at 24.3078 -293.2176 180)
		(property "Reference" "R573"
			(at 0 0 180)
			(layer "F.SilkS")
			(hide yes)
			(effects
				(font
					(size 1.27 1.27)
				)
			)
		)
		(property "Value" "300KR2F-GP"
			(at 0.064008 -3.993896 180)
			(unlocked yes)
			(layer "F.Fab")
			(hide yes)
			(effects
				(font
					(size 1.016 1.016)
					(thickness 0.1524)
				)
			)
		)
		(property "Device Type" "R402H16"
			(at 0.064008 -5.517896 180)
			(unlocked yes)
			(layer "F.Fab")
			(hide yes)
			(effects
				(font
					(size 1.016 1.016)
					(thickness 0.1524)
				)
			)
		)
		(duplicate_pad_numbers_are_jumpers no)
		(fp_line
			(start 0.508 -0.9398)
			(end -0.508 -0.9398)
			(stroke
				(width 0.1524)
				(type default)
			)
			(layer "F.SilkS")
		)
		(fp_line
			(start -0.508 -0.9398)
			(end -0.508 0.9398)
			(stroke
				(width 0.1524)
				(type default)
			)
			(layer "F.SilkS")
		)
		(fp_rect
			(start -0.508 0.9398)
			(end 0.508 -0.9398)
			(stroke
				(width 0)
				(type default)
			)
			(fill no)
			(layer "F.CrtYd")
		)
		(fp_rect
			(start -0.508 0.9398)
			(end 0.508 -0.9398)
			(stroke
				(width 0)
				(type default)
			)
			(fill no)
			(layer "F.Fab")
		)
		(pad "1" smd custom
			(at 0 -0.4445 180)
			(size 0.1397 0.1397)
			(layers "F.Cu" "F.Mask" "F.Paste")
			(net "SW_SSD7_N")
			(options
				(clearance outline)
				(anchor circle)
			)
			(primitives
				(gr_poly
					(pts
						(arc
							(start -0.1778 -0.2794)
							(mid -0.249642 -0.249642)
							(end -0.2794 -0.1778)
						)
						(arc
							(start -0.2794 0.1778)
							(mid -0.249642 0.249642)
							(end -0.1778 0.2794)
						)
						(arc
							(start 0.1778 0.2794)
							(mid 0.249642 0.249642)
							(end 0.2794 0.1778)
						)
						(arc
							(start 0.2794 -0.1778)
							(mid 0.249642 -0.249642)
							(end 0.1778 -0.2794)
						)
					)
					(width 0)
					(fill yes)
				)
			)
		)
		(pad "2" smd custom
			(at 0 0.4445 180)
			(size 0.1397 0.1397)
			(layers "F.Cu" "F.Mask" "F.Paste")
			(net "P12V")
			(options
				(clearance outline)
				(anchor circle)
			)
			(primitives
				(gr_poly
					(pts
						(arc
							(start -0.1778 -0.2794)
							(mid -0.249642 -0.249642)
							(end -0.2794 -0.1778)
						)
						(arc
							(start -0.2794 0.1778)
							(mid -0.249642 0.249642)
							(end -0.1778 0.2794)
						)
						(arc
							(start 0.1778 0.2794)
							(mid 0.249642 0.249642)
							(end 0.2794 0.1778)
						)
						(arc
							(start 0.2794 -0.1778)
							(mid 0.249642 -0.249642)
							(end 0.1778 -0.2794)
						)
					)
					(width 0)
					(fill yes)
				)
			)
		)
	)
	(footprint ""
		(layer "F.Cu")
		(at 10.6172 -498.4242)
		(property "Reference" "R9765"
			(at 0 0 0)
			(layer "F.SilkS")
			(hide yes)
			(effects
				(font
					(size 1.27 1.27)
				)
			)
		)
		(property "Value" "4K7R2J-2-GP"
			(at 0.064008 -3.993896 0)
			(unlocked yes)
			(layer "F.Fab")
			(hide yes)
			(effects
				(font
					(size 1.016 1.016)
					(thickness 0.1524)
				)
			)
		)
		(property "Device Type" "R402H16"
			(at 0.064008 -5.517896 0)
			(unlocked yes)
			(layer "F.Fab")
			(hide yes)
			(effects
				(font
					(size 1.016 1.016)
					(thickness 0.1524)
				)
			)
		)
		(duplicate_pad_numbers_are_jumpers no)
		(fp_line
			(start -0.508 -0.9398)
			(end -0.508 0.9398)
			(stroke
				(width 0.1524)
				(type default)
			)
			(layer "F.SilkS")
		)
		(fp_line
			(start 0.508 -0.9398)
			(end -0.508 -0.9398)
			(stroke
				(width 0.1524)
				(type default)
			)
			(layer "F.SilkS")
		)
		(fp_rect
			(start -0.508 0.9398)
			(end 0.508 -0.9398)
			(stroke
				(width 0)
				(type default)
			)
			(fill no)
			(layer "F.CrtYd")
		)
		(fp_rect
			(start -0.508 0.9398)
			(end 0.508 -0.9398)
			(stroke
				(width 0)
				(type default)
			)
			(fill no)
			(layer "F.Fab")
		)
		(pad "1" smd custom
			(at 0 -0.4445)
			(size 0.1397 0.1397)
			(layers "F.Cu" "F.Mask" "F.Paste")
			(net "SSD5_PWREN")
			(options
				(clearance outline)
				(anchor circle)
			)
			(primitives
				(gr_poly
					(pts
						(arc
							(start -0.1778 -0.2794)
							(mid -0.249642 -0.249642)
							(end -0.2794 -0.1778)
						)
						(arc
							(start -0.2794 0.1778)
							(mid -0.249642 0.249642)
							(end -0.1778 0.2794)
						)
						(arc
							(start 0.1778 0.2794)
							(mid 0.249642 0.249642)
							(end 0.2794 0.1778)
						)
						(arc
							(start 0.2794 -0.1778)
							(mid 0.249642 -0.249642)
							(end 0.1778 -0.2794)
						)
					)
					(width 0)
					(fill yes)
				)
			)
		)
		(pad "2" smd custom
			(at 0 0.4445)
			(size 0.1397 0.1397)
			(layers "F.Cu" "F.Mask" "F.Paste")
			(net "GND")
			(options
				(clearance outline)
				(anchor circle)
			)
			(primitives
				(gr_poly
					(pts
						(arc
							(start -0.1778 -0.2794)
							(mid -0.249642 -0.249642)
							(end -0.2794 -0.1778)
						)
						(arc
							(start -0.2794 0.1778)
							(mid -0.249642 0.249642)
							(end -0.1778 0.2794)
						)
						(arc
							(start 0.1778 0.2794)
							(mid 0.249642 0.249642)
							(end 0.2794 0.1778)
						)
						(arc
							(start 0.2794 -0.1778)
							(mid 0.249642 -0.249642)
							(end 0.1778 -0.2794)
						)
					)
					(width 0)
					(fill yes)
				)
			)
		)
	)
	(footprint ""
		(layer "F.Cu")
		(at 98.552 -440.055)
		(property "Reference" "R9582"
			(at 0 0 0)
			(layer "F.SilkS")
			(hide yes)
			(effects
				(font
					(size 1.27 1.27)
				)
			)
		)
		(property "Value" "0R5J-L1-GP"
			(at 0 -8.9535 0)
			(unlocked yes)
			(layer "F.Fab")
			(hide yes)
			(effects
				(font
					(size 1.27 1.016)
					(thickness 0.1524)
				)
			)
		)
		(property "Device Type" "R805H24"
			(at 0 -10.6299 0)
			(unlocked yes)
			(layer "F.Fab")
			(hide yes)
			(effects
				(font
					(size 1.27 1.016)
					(thickness 0.1524)
				)
			)
		)
		(duplicate_pad_numbers_are_jumpers no)
		(fp_line
			(start -0.889 -1.7018)
			(end -0.889 0.2794)
			(stroke
				(width 0.1524)
				(type default)
			)
			(layer "F.SilkS")
		)
		(fp_line
			(start -0.889 0.0762)
			(end -0.889 1.7018)
			(stroke
				(width 0.1524)
				(type default)
			)
			(layer "F.SilkS")
		)
		(fp_line
			(start -0.889 1.7018)
			(end 0.889 1.7018)
			(stroke
				(width 0.1524)
				(type default)
			)
			(layer "F.SilkS")
		)
		(fp_line
			(start 0.889 -1.7018)
			(end -0.889 -1.7018)
			(stroke
				(width 0.1524)
				(type default)
			)
			(layer "F.SilkS")
		)
		(fp_line
			(start 0.889 -1.7018)
			(end 0.889 -0.381)
			(stroke
				(width 0.1524)
				(type default)
			)
			(layer "F.SilkS")
		)
		(fp_line
			(start 0.889 1.7018)
			(end 0.889 -0.508)
			(stroke
				(width 0.1524)
				(type default)
			)
			(layer "F.SilkS")
		)
		(fp_poly
			(pts
				(xy 0.9652 -1.778) (xy 0.9652 1.778) (xy -0.9652 1.778) (xy -0.9652 -1.778)
			)
			(stroke
				(width 0)
				(type default)
			)
			(fill no)
			(layer "F.CrtYd")
		)
		(fp_rect
			(start -0.9652 1.778)
			(end 0.9652 -1.778)
			(stroke
				(width 0)
				(type default)
			)
			(fill no)
			(layer "F.Fab")
		)
		(pad "1" smd rect
			(at 0 -0.9652)
			(size 1.397 1.143)
			(layers "F.Cu" "F.Mask" "F.Paste")
			(net "P3V3")
		)
		(pad "2" smd rect
			(at 0 0.9652)
			(size 1.397 1.143)
			(layers "F.Cu" "F.Mask" "F.Paste")
			(net "VDD_IO_1")
		)
	)
	(footprint ""
		(layer "F.Cu")
		(at 253.499874 -483.497636)
		(property "Reference" "H12"
			(at 0 0 0)
			(layer "F.SilkS")
			(hide yes)
			(effects
				(font
					(size 1.27 1.27)
				)
			)
		)
		(property "Value" "GEN276X162R197X296-6-F-A-GP"
			(at -6.7183 4.1402 0)
			(unlocked yes)
			(layer "F.Fab")
			(hide yes)
			(effects
				(font
					(size 1.016 1.016)
					(thickness 0.1524)
				)
			)
		)
		(property "Device Type" "GEN276X162R197X296-6-F-A"
			(at -6.7183 2.6162 0)
			(unlocked yes)
			(layer "F.Fab")
			(hide yes)
			(effects
				(font
					(size 1.016 1.016)
					(thickness 0.1524)
				)
			)
		)
		(duplicate_pad_numbers_are_jumpers no)
		(fp_poly
			(pts
				(arc
					(start 2.723642 4.777232)
					(mid -0.000169 6.508462)
					(end -2.723896 4.776978)
				)
				(arc
					(start -2.723896 4.776978)
					(mid 0.000173 -5.499012)
					(end 2.723642 4.777232)
				)
			)
			(stroke
				(width 0)
				(type default)
			)
			(fill no)
			(layer "B.CrtYd")
		)
		(fp_poly
			(pts
				(arc
					(start 2.723642 4.777232)
					(mid -0.000169 6.508462)
					(end -2.723896 4.776978)
				)
				(arc
					(start -2.723896 4.776978)
					(mid 0.000173 -5.499012)
					(end 2.723642 4.777232)
				)
			)
			(stroke
				(width 0)
				(type default)
			)
			(fill no)
			(layer "F.CrtYd")
		)
		(fp_poly
			(pts
				(arc
					(start 2.723642 4.777232)
					(mid -0.000169 6.508462)
					(end -2.723896 4.776978)
				)
				(arc
					(start -2.723896 4.776978)
					(mid 0.000173 -5.499012)
					(end 2.723642 4.777232)
				)
			)
			(stroke
				(width 0)
				(type default)
			)
			(fill no)
			(layer "B.Fab")
		)
		(fp_poly
			(pts
				(arc
					(start 2.723642 4.777232)
					(mid -0.000169 6.508462)
					(end -2.723896 4.776978)
				)
				(arc
					(start -2.723896 4.776978)
					(mid 0.000173 -5.499012)
					(end 2.723642 4.777232)
				)
			)
			(stroke
				(width 0)
				(type default)
			)
			(fill no)
			(layer "F.Fab")
		)
		(pad "" np_thru_hole circle
			(at 0 0)
			(size 0.254 0.254)
			(drill 0.0254)
			(layers "*.Cu" "*.Mask")
			(clearance 3.135376)
			(thermal_gap 3.135376)
		)
		(pad "1" thru_hole circle
			(at 2.549906 0)
			(size 0.8636 0.8636)
			(drill 0.508)
			(layers "*.Cu" "*.Mask")
			(remove_unused_layers no)
			(net "GND")
			(clearance 0.8255)
			(thermal_gap 0.8255)
		)
		(pad "2" thru_hole circle
			(at 2.210054 -1.27)
			(size 0.8636 0.8636)
			(drill 0.508)
			(layers "*.Cu" "*.Mask")
			(remove_unused_layers no)
			(net "GND")
			(clearance 0.8255)
			(thermal_gap 0.8255)
		)
		(pad "3" thru_hole circle
			(at 1.27 -2.210054)
			(size 0.8636 0.8636)
			(drill 0.508)
			(layers "*.Cu" "*.Mask")
			(remove_unused_layers no)
			(net "GND")
			(clearance 0.8255)
			(thermal_gap 0.8255)
		)
		(pad "4" thru_hole circle
			(at -1.279906 -2.210054)
			(size 0.8636 0.8636)
			(drill 0.508)
			(layers "*.Cu" "*.Mask")
			(remove_unused_layers no)
			(net "GND")
			(clearance 0.8255)
			(thermal_gap 0.8255)
		)
		(pad "5" thru_hole circle
			(at -2.210054 -1.27)
			(size 0.8636 0.8636)
			(drill 0.508)
			(layers "*.Cu" "*.Mask")
			(remove_unused_layers no)
			(net "GND")
			(clearance 0.8255)
			(thermal_gap 0.8255)
		)
		(pad "6" thru_hole circle
			(at -2.549906 0)
			(size 0.8636 0.8636)
			(drill 0.508)
			(layers "*.Cu" "*.Mask")
			(remove_unused_layers no)
			(net "GND")
			(clearance 0.8255)
			(thermal_gap 0.8255)
		)
		(zone
			(layers "F.Cu" "B.Cu" "In1.Cu" "In2.Cu" "In3.Cu" "In4.Cu" "In5.Cu" "In6.Cu")
			(hatch none 0.5)
			(connect_pads
				(clearance 0)
			)
			(min_thickness 0.25)
			(keepout
				(tracks allowed)
				(vias not_allowed)
				(pads allowed)
				(copperpour not_allowed)
				(footprints allowed)
			)
			(placement
				(enabled no)
				(sheetname "")
			)
			(fill
				(thermal_gap 0.5)
				(thermal_bridge_width 0.5)
				(island_removal_mode 0)
			)
			(polygon
				(pts
					(arc
						(start 257.817874 -483.500684)
						(mid 249.181874 -483.500684)
						(end 257.817874 -483.500684)
					)
				)
			)
		)
		(zone
			(layers "F.Cu" "B.Cu" "In1.Cu" "In2.Cu" "In3.Cu" "In4.Cu" "In5.Cu" "In6.Cu")
			(hatch none 0.5)
			(connect_pads
				(clearance 0)
			)
			(min_thickness 0.25)
			(keepout
				(tracks not_allowed)
				(vias allowed)
				(pads allowed)
				(copperpour not_allowed)
				(footprints allowed)
			)
			(placement
				(enabled no)
				(sheetname "")
			)
			(fill
				(thermal_gap 0.5)
				(thermal_bridge_width 0.5)
				(island_removal_mode 0)
			)
			(polygon
				(pts
					(arc
						(start 255.839214 -481.888292)
						(mid 253.499954 -476.989189)
						(end 251.16028 -481.888292)
					)
					(arc
						(start 251.16028 -481.888292)
						(mid 251.406247 -482.328658)
						(end 251.491496 -482.825806)
					)
					(arc
						(start 251.491496 -483.497636)
						(mid 253.499874 -485.506014)
						(end 255.507998 -483.497636)
					)
					(arc
						(start 255.507998 -482.825806)
						(mid 255.593233 -482.328652)
						(end 255.839214 -481.888292)
					)
				)
			)
		)
	)
	(footprint ""
		(layer "F.Cu")
		(at 207.01 -454.66 180)
		(property "Reference" "R317"
			(at 0 0 180)
			(layer "F.SilkS")
			(hide yes)
			(effects
				(font
					(size 1.27 1.27)
				)
			)
		)
		(property "Value" "4K7R2J-2-GP"
			(at 0.064008 -3.993896 180)
			(unlocked yes)
			(layer "F.Fab")
			(hide yes)
			(effects
				(font
					(size 1.016 1.016)
					(thickness 0.1524)
				)
			)
		)
		(property "Device Type" "R402H16"
			(at 0.064008 -5.517896 180)
			(unlocked yes)
			(layer "F.Fab")
			(hide yes)
			(effects
				(font
					(size 1.016 1.016)
					(thickness 0.1524)
				)
			)
		)
		(duplicate_pad_numbers_are_jumpers no)
		(fp_line
			(start 0.508 -0.9398)
			(end -0.508 -0.9398)
			(stroke
				(width 0.1524)
				(type default)
			)
			(layer "F.SilkS")
		)
		(fp_line
			(start -0.508 -0.9398)
			(end -0.508 0.9398)
			(stroke
				(width 0.1524)
				(type default)
			)
			(layer "F.SilkS")
		)
		(fp_rect
			(start -0.508 0.9398)
			(end 0.508 -0.9398)
			(stroke
				(width 0)
				(type default)
			)
			(fill no)
			(layer "F.CrtYd")
		)
		(fp_rect
			(start -0.508 0.9398)
			(end 0.508 -0.9398)
			(stroke
				(width 0)
				(type default)
			)
			(fill no)
			(layer "F.Fab")
		)
		(pad "1" smd custom
			(at 0 -0.4445 180)
			(size 0.1397 0.1397)
			(layers "F.Cu" "F.Mask" "F.Paste")
			(net "P3V3")
			(options
				(clearance outline)
				(anchor circle)
			)
			(primitives
				(gr_poly
					(pts
						(arc
							(start -0.1778 -0.2794)
							(mid -0.249642 -0.249642)
							(end -0.2794 -0.1778)
						)
						(arc
							(start -0.2794 0.1778)
							(mid -0.249642 0.249642)
							(end -0.1778 0.2794)
						)
						(arc
							(start 0.1778 0.2794)
							(mid 0.249642 0.249642)
							(end 0.2794 0.1778)
						)
						(arc
							(start 0.2794 -0.1778)
							(mid 0.249642 -0.249642)
							(end 0.1778 -0.2794)
						)
					)
					(width 0)
					(fill yes)
				)
			)
		)
		(pad "2" smd custom
			(at 0 0.4445 180)
			(size 0.1397 0.1397)
			(layers "F.Cu" "F.Mask" "F.Paste")
			(net "I2C_B_TMP2_A0")
			(options
				(clearance outline)
				(anchor circle)
			)
			(primitives
				(gr_poly
					(pts
						(arc
							(start -0.1778 -0.2794)
							(mid -0.249642 -0.249642)
							(end -0.2794 -0.1778)
						)
						(arc
							(start -0.2794 0.1778)
							(mid -0.249642 0.249642)
							(end -0.1778 0.2794)
						)
						(arc
							(start 0.1778 0.2794)
							(mid 0.249642 0.249642)
							(end 0.2794 0.1778)
						)
						(arc
							(start 0.2794 -0.1778)
							(mid 0.249642 -0.249642)
							(end 0.1778 -0.2794)
						)
					)
					(width 0)
					(fill yes)
				)
			)
		)
	)
)
